# T6G (Grand Teton) — schematic netlist excerpt (pin names and nets, part order shuffled) for the footprints in the layout excerpt that follows; sources: Cadence DE-HDL packaged netlist, KiCad conversion of 04192023_DAF0TMB3IC0_F0TG_MB_C_brd_V02_OCP.brd

PR4005  Q_RES  30.1K 1% CHIP  pkg 0402LF  page 152 : A = P12V_SCM_IMON ; B = GND
PC93  Q_CAP  0.1UF 25V 10% X7R  pkg 0402  page 217 : A = PVDDCR_CPU1_P1_VCCS ; B = GND
R1017  Q_RES  1K 1% EMPTY  pkg 0201LF  page 287 : A = P1V8_CPU0_RT_1D ; B = RT_CPU0_P1_ADDR1

(kicad_pcb
	(version 20260206)
	(generator "pcbnew")
	(generator_version "10.0")
	(general
		(thickness 1.6)
		(legacy_teardrops no)
	)
	(paper "A4")
	(title_block
		(title "04192023_DAF0TMB3IC0_F0TG_MB_C_brd_V02_OCP.brd")
		(comment 1 "Grand Teton / footprints 4425-4427 of 8354")
	)
	(layers
		(0 "F.Cu" signal "TOP")
		(4 "In1.Cu" signal "GND")
		(6 "In2.Cu" signal "IN1")
		(8 "In3.Cu" signal "GND1")
		(10 "In4.Cu" signal "IN2")
		(12 "In5.Cu" signal "GND2")
		(14 "In6.Cu" signal "IN3")
		(16 "In7.Cu" signal "GND3")
		(18 "In8.Cu" signal "VCC")
		(20 "In9.Cu" signal "VCC1")
		(22 "In10.Cu" signal "GND4")
		(24 "In11.Cu" signal "IN4")
		(26 "In12.Cu" signal "GND5")
		(28 "In13.Cu" signal "IN5")
		(30 "In14.Cu" signal "GND6")
		(32 "In15.Cu" signal "IN6")
		(34 "In16.Cu" signal "GND7")
		(2 "B.Cu" signal "BOTTOM")
		(9 "F.Adhes" user "F.Adhesive")
		(11 "B.Adhes" user "B.Adhesive")
		(13 "F.Paste" user "Package Geometry/Pastemask Top")
		(15 "B.Paste" user "Package Geometry/Pastemask Bottom")
		(5 "F.SilkS" user "Ref Des/Silkscreen Top")
		(7 "B.SilkS" user "Ref Des/Silkscreen Bottom")
		(1 "F.Mask" user "Board Geometry/Soldermask Top")
		(3 "B.Mask" user "Board Geometry/Soldermask Bottom")
		(17 "Dwgs.User" user "User.Drawings")
		(19 "Cmts.User" user "User.Comments")
		(21 "Eco1.User" user "User.Eco1")
		(23 "Eco2.User" user "User.Eco2")
		(25 "Edge.Cuts" user "Board Geometry/Outline")
		(27 "Margin" user)
		(31 "F.CrtYd" user "Package Geometry/Place Bound Top")
		(29 "B.CrtYd" user "Package Geometry/Place Bound Bottom")
		(35 "F.Fab" user "Ref Des/Assembly Top")
		(33 "B.Fab" user "Ref Des/Assembly Bottom")
	)
	(footprint ""
		(layer "F.Cu")
		(at 33.81248 -368.467132 90)
		(property "Reference" "PC93"
			(at 0 0 90)
			(layer "F.SilkS")
			(hide yes)
			(effects
				(font
					(size 1.27 1.27)
				)
			)
		)
		(property "Value" ""
			(at 0 0 90)
			(layer "F.Fab")
			(effects
				(font
					(size 1.27 1.27)
				)
			)
		)
		(duplicate_pad_numbers_are_jumpers no)
		(fp_line
			(start 0.7874 -0.4064)
			(end 0.7874 0.4064)
			(stroke
				(width 0.1524)
				(type default)
			)
			(layer "F.SilkS")
		)
		(fp_line
			(start -0.7874 -0.4064)
			(end 0.7874 -0.4064)
			(stroke
				(width 0.1524)
				(type default)
			)
			(layer "F.SilkS")
		)
		(fp_line
			(start 0.7874 0.4064)
			(end -0.7874 0.4064)
			(stroke
				(width 0.1524)
				(type default)
			)
			(layer "F.SilkS")
		)
		(fp_line
			(start -0.7874 0.4064)
			(end -0.7874 -0.4064)
			(stroke
				(width 0.1524)
				(type default)
			)
			(layer "F.SilkS")
		)
		(fp_line
			(start -0.12065 -0.305054)
			(end -0.12065 -0.2794)
			(stroke
				(width 0.1)
				(type default)
			)
			(layer "F.Fab")
		)
		(fp_line
			(start -0.67945 -0.305054)
			(end -0.12065 -0.305054)
			(stroke
				(width 0.1)
				(type default)
			)
			(layer "F.Fab")
		)
		(fp_line
			(start 0.67945 -0.3048)
			(end 0.67945 0.3048)
			(stroke
				(width 0.1)
				(type default)
			)
			(layer "F.Fab")
		)
		(fp_line
			(start 0.12065 -0.3048)
			(end 0.67945 -0.3048)
			(stroke
				(width 0.1)
				(type default)
			)
			(layer "F.Fab")
		)
		(fp_line
			(start 0.12065 -0.2794)
			(end 0.12065 -0.3048)
			(stroke
				(width 0.1)
				(type default)
			)
			(layer "F.Fab")
		)
		(fp_line
			(start -0.12065 -0.2794)
			(end 0.12065 -0.2794)
			(stroke
				(width 0.1)
				(type default)
			)
			(layer "F.Fab")
		)
		(fp_line
			(start 0.120396 0.2794)
			(end -0.12065 0.2794)
			(stroke
				(width 0.1)
				(type default)
			)
			(layer "F.Fab")
		)
		(fp_line
			(start -0.12065 0.2794)
			(end -0.12065 0.3048)
			(stroke
				(width 0.1)
				(type default)
			)
			(layer "F.Fab")
		)
		(fp_line
			(start 0.67945 0.3048)
			(end 0.120396 0.3048)
			(stroke
				(width 0.1)
				(type default)
			)
			(layer "F.Fab")
		)
		(fp_line
			(start 0.120396 0.3048)
			(end 0.120396 0.2794)
			(stroke
				(width 0.1)
				(type default)
			)
			(layer "F.Fab")
		)
		(fp_line
			(start -0.12065 0.3048)
			(end -0.67945 0.3048)
			(stroke
				(width 0.1)
				(type default)
			)
			(layer "F.Fab")
		)
		(fp_line
			(start -0.67945 0.3048)
			(end -0.67945 -0.305054)
			(stroke
				(width 0.1)
				(type default)
			)
			(layer "F.Fab")
		)
		(pad "1" smd circle
			(at -0.40005 0 90)
			(size 0 0)
			(layers "F.Cu" "F.Mask" "F.Paste")
			(net "PVDDCR_CPU1_P1_VCCS")
		)
		(pad "2" smd circle
			(at 0.40005 0 90)
			(size 0 0)
			(layers "F.Cu" "F.Mask" "F.Paste")
			(net "GND")
		)
	)
	(footprint ""
		(layer "F.Cu")
		(at 173.597062 -32.935672 90)
		(property "Reference" "PR4005"
			(at 0 0 90)
			(layer "F.SilkS")
			(hide yes)
			(effects
				(font
					(size 1.27 1.27)
				)
			)
		)
		(property "Value" ""
			(at 0 0 90)
			(layer "F.Fab")
			(effects
				(font
					(size 1.27 1.27)
				)
			)
		)
		(duplicate_pad_numbers_are_jumpers no)
		(fp_line
			(start 0.7874 -0.4064)
			(end 0.7874 0.4064)
			(stroke
				(width 0.1524)
				(type default)
			)
			(layer "F.SilkS")
		)
		(fp_line
			(start -0.7874 -0.4064)
			(end 0.7874 -0.4064)
			(stroke
				(width 0.1524)
				(type default)
			)
			(layer "F.SilkS")
		)
		(fp_line
			(start 0.7874 0.4064)
			(end -0.7874 0.4064)
			(stroke
				(width 0.1524)
				(type default)
			)
			(layer "F.SilkS")
		)
		(fp_line
			(start -0.7874 0.4064)
			(end -0.7874 -0.4064)
			(stroke
				(width 0.1524)
				(type default)
			)
			(layer "F.SilkS")
		)
		(fp_line
			(start -0.12065 -0.305054)
			(end -0.12065 -0.2794)
			(stroke
				(width 0.1)
				(type default)
			)
			(layer "F.Fab")
		)
		(fp_line
			(start -0.67945 -0.305054)
			(end -0.12065 -0.305054)
			(stroke
				(width 0.1)
				(type default)
			)
			(layer "F.Fab")
		)
		(fp_line
			(start 0.67945 -0.3048)
			(end 0.67945 0.3048)
			(stroke
				(width 0.1)
				(type default)
			)
			(layer "F.Fab")
		)
		(fp_line
			(start 0.12065 -0.3048)
			(end 0.67945 -0.3048)
			(stroke
				(width 0.1)
				(type default)
			)
			(layer "F.Fab")
		)
		(fp_line
			(start 0.12065 -0.2794)
			(end 0.12065 -0.3048)
			(stroke
				(width 0.1)
				(type default)
			)
			(layer "F.Fab")
		)
		(fp_line
			(start -0.12065 -0.2794)
			(end 0.12065 -0.2794)
			(stroke
				(width 0.1)
				(type default)
			)
			(layer "F.Fab")
		)
		(fp_line
			(start 0.120396 0.2794)
			(end -0.12065 0.2794)
			(stroke
				(width 0.1)
				(type default)
			)
			(layer "F.Fab")
		)
		(fp_line
			(start -0.12065 0.2794)
			(end -0.12065 0.3048)
			(stroke
				(width 0.1)
				(type default)
			)
			(layer "F.Fab")
		)
		(fp_line
			(start 0.67945 0.3048)
			(end 0.120396 0.3048)
			(stroke
				(width 0.1)
				(type default)
			)
			(layer "F.Fab")
		)
		(fp_line
			(start 0.120396 0.3048)
			(end 0.120396 0.2794)
			(stroke
				(width 0.1)
				(type default)
			)
			(layer "F.Fab")
		)
		(fp_line
			(start -0.12065 0.3048)
			(end -0.67945 0.3048)
			(stroke
				(width 0.1)
				(type default)
			)
			(layer "F.Fab")
		)
		(fp_line
			(start -0.67945 0.3048)
			(end -0.67945 -0.305054)
			(stroke
				(width 0.1)
				(type default)
			)
			(layer "F.Fab")
		)
		(pad "1" smd circle
			(at -0.40005 0 90)
			(size 0 0)
			(layers "F.Cu" "F.Mask" "F.Paste")
			(net "P12V_SCM_IMON")
		)
		(pad "2" smd circle
			(at 0.40005 0 90)
			(size 0 0)
			(layers "F.Cu" "F.Mask" "F.Paste")
			(net "GND")
		)
	)
	(footprint ""
		(layer "F.Cu")
		(at 359.49509 -391.0584 180)
		(property "Reference" "R1017"
			(at 0 0 180)
			(layer "F.SilkS")
			(hide yes)
			(effects
				(font
					(size 1.27 1.27)
				)
			)
		)
		(property "Value" ""
			(at 0 0 180)
			(layer "F.Fab")
			(effects
				(font
					(size 1.27 1.27)
				)
			)
		)
		(duplicate_pad_numbers_are_jumpers no)
		(fp_line
			(start 0.32512 0.175006)
			(end -0.32512 0.175006)
			(stroke
				(width 0.1)
				(type default)
			)
			(layer "F.Fab")
		)
		(fp_line
			(start 0.32512 -0.175006)
			(end 0.32512 0.175006)
			(stroke
				(width 0.1)
				(type default)
			)
			(layer "F.Fab")
		)
		(fp_line
			(start -0.32512 0.175006)
			(end -0.32512 -0.175006)
			(stroke
				(width 0.1)
				(type default)
			)
			(layer "F.Fab")
		)
		(fp_line
			(start -0.32512 -0.175006)
			(end 0.32512 -0.175006)
			(stroke
				(width 0.1)
				(type default)
			)
			(layer "F.Fab")
		)
		(pad "1" smd rect
			(at -0.2667 0 180)
			(size 0.3048 0.381)
			(layers "F.Cu" "F.Mask" "F.Paste")
			(net "P1V8_CPU0_RT_1D")
		)
		(pad "2" smd rect
			(at 0.2667 0)
			(size 0.3048 0.381)
			(layers "F.Cu" "F.Mask" "F.Paste")
			(net "RT_CPU0_P1_ADDR1")
		)
	)
)
